(kicad_pcb
	(version 20260206)
	(generator "pcbnew")
	(generator_version "10.0")
	(general
		(thickness 1.6)
		(legacy_teardrops no)
	)
	(paper "A4")
	(title_block
		(title "03242023_DA0F0TMBIJ0_F0T_Motherboard_J_brd_V01_OCP.brd")
		(comment 1 "Grand Teton / footprints 2498-2504 of 6105")
	)
	(layers
		(0 "F.Cu" signal "TOP")
		(4 "In1.Cu" signal "GND")
		(6 "In2.Cu" signal "IN1")
		(8 "In3.Cu" signal "GND1")
		(10 "In4.Cu" signal "IN2")
		(12 "In5.Cu" signal "GND2")
		(14 "In6.Cu" signal "IN3")
		(16 "In7.Cu" signal "GND3")
		(18 "In8.Cu" signal "VCC")
		(20 "In9.Cu" signal "VCC1")
		(22 "In10.Cu" signal "GND4")
		(24 "In11.Cu" signal "IN4")
		(26 "In12.Cu" signal "GND5")
		(28 "In13.Cu" signal "IN5")
		(30 "In14.Cu" signal "GND6")
		(32 "In15.Cu" signal "IN6")
		(34 "In16.Cu" signal "GND7")
		(2 "B.Cu" signal "BOTTOM")
		(9 "F.Adhes" user "F.Adhesive")
		(11 "B.Adhes" user "B.Adhesive")
		(13 "F.Paste" user "Package Geometry/Pastemask Top")
		(15 "B.Paste" user "Package Geometry/Pastemask Bottom")
		(5 "F.SilkS" user "Ref Des/Silkscreen Top")
		(7 "B.SilkS" user "Ref Des/Silkscreen Bottom")
		(1 "F.Mask" user "Board Geometry/Soldermask Top")
		(3 "B.Mask" user "Board Geometry/Soldermask Bottom")
		(17 "Dwgs.User" user "User.Drawings")
		(19 "Cmts.User" user "User.Comments")
		(21 "Eco1.User" user "User.Eco1")
		(23 "Eco2.User" user "User.Eco2")
		(25 "Edge.Cuts" user "Board Geometry/Outline")
		(27 "Margin" user)
		(31 "F.CrtYd" user "Package Geometry/Place Bound Top")
		(29 "B.CrtYd" user "Package Geometry/Place Bound Bottom")
		(35 "F.Fab" user "Ref Des/Assembly Top")
		(33 "B.Fab" user "Ref Des/Assembly Bottom")
	)
	(footprint ""
		(layer "F.Cu")
		(at 131.68122 -75.85837 -90)
		(property "Reference" "D141"
			(at -4.793488 -2.42316 0)
			(unlocked yes)
			(layer "F.SilkS")
			(effects
				(font
					(size 0.7874 0.5842)
					(thickness 0.1524)
				)
				(justify left)
			)
		)
		(property "Value" ""
			(at 0 0 270)
			(layer "F.Fab")
			(effects
				(font
					(size 1.27 1.27)
				)
			)
		)
		(duplicate_pad_numbers_are_jumpers no)
		(fp_line
			(start -2.4638 1.0414)
			(end -2.4638 -1.0414)
			(stroke
				(width 0.1524)
				(type default)
			)
			(layer "F.SilkS")
		)
		(fp_line
			(start 2.7178 1.0414)
			(end -2.4638 1.0414)
			(stroke
				(width 0.1524)
				(type default)
			)
			(layer "F.SilkS")
		)
		(fp_line
			(start -0.508 0.5334)
			(end 0.1778 -0.0254)
			(stroke
				(width 0.1524)
				(type default)
			)
			(layer "F.SilkS")
		)
		(fp_line
			(start 0.1778 -0.0254)
			(end -0.4826 -0.4826)
			(stroke
				(width 0.1524)
				(type default)
			)
			(layer "F.SilkS")
		)
		(fp_line
			(start -0.508 -0.508)
			(end -0.508 0.5334)
			(stroke
				(width 0.1524)
				(type default)
			)
			(layer "F.SilkS")
		)
		(fp_line
			(start 0.254 -0.508)
			(end 0.254 0.5334)
			(stroke
				(width 0.1524)
				(type default)
			)
			(layer "F.SilkS")
		)
		(fp_line
			(start -2.4638 -1.0414)
			(end 2.7178 -1.0414)
			(stroke
				(width 0.1524)
				(type default)
			)
			(layer "F.SilkS")
		)
		(fp_line
			(start 2.4638 -1.0414)
			(end 2.4638 1.0414)
			(stroke
				(width 0.1524)
				(type default)
			)
			(layer "F.SilkS")
		)
		(fp_line
			(start 2.5908 -1.0414)
			(end 2.5908 1.0414)
			(stroke
				(width 0.1524)
				(type default)
			)
			(layer "F.SilkS")
		)
		(fp_line
			(start 2.7178 -1.0414)
			(end 2.7178 1.0414)
			(stroke
				(width 0.1524)
				(type default)
			)
			(layer "F.SilkS")
		)
		(fp_line
			(start -2.4638 1.0414)
			(end -2.4638 -1.0414)
			(stroke
				(width 0.1)
				(type default)
			)
			(layer "F.Fab")
		)
		(fp_line
			(start 2.7178 1.0414)
			(end -2.4638 1.0414)
			(stroke
				(width 0.1)
				(type default)
			)
			(layer "F.Fab")
		)
		(fp_line
			(start -2.4638 -1.0414)
			(end 2.7178 -1.0414)
			(stroke
				(width 0.1)
				(type default)
			)
			(layer "F.Fab")
		)
		(fp_line
			(start 2.7178 -1.0414)
			(end 2.7178 1.0414)
			(stroke
				(width 0.1)
				(type default)
			)
			(layer "F.Fab")
		)
		(fp_text user "-"
			(at 2.538222 1.24841 270)
			(unlocked yes)
			(layer "F.SilkS")
			(effects
				(font
					(size 1.905 1.4224)
					(thickness 0.1524)
				)
				(justify left)
			)
		)
		(fp_text user "+"
			(at -3.9624 -0.17145 270)
			(unlocked yes)
			(layer "F.SilkS")
			(effects
				(font
					(size 1.905 1.4224)
					(thickness 0.1524)
				)
				(justify left)
			)
		)
		(fp_text user "+"
			(at -3.9624 -0.17145 270)
			(unlocked yes)
			(layer "F.Fab")
			(effects
				(font
					(size 1.905 1.4224)
					(thickness 0.1524)
				)
				(justify left)
			)
		)
		(fp_text user "-"
			(at 2.9845 -0.366268 270)
			(unlocked yes)
			(layer "F.Fab")
			(effects
				(font
					(size 1.905 1.4224)
					(thickness 0.1524)
				)
				(justify left)
			)
		)
		(pad "1" smd rect
			(at -1.724914 0 270)
			(size 1.1684 1.7526)
			(layers "F.Cu" "F.Mask" "F.Paste")
			(net "P3V3_AUX")
		)
		(pad "2" smd rect
			(at 1.724914 0 270)
			(size 1.1684 1.7526)
			(layers "F.Cu" "F.Mask" "F.Paste")
			(net "P3V3_AUX_BMC_D")
		)
	)
	(footprint ""
		(layer "F.Cu")
		(at 111.095282 -406.058116 -90)
		(property "Reference" "R3494"
			(at 0 0 270)
			(layer "F.SilkS")
			(hide yes)
			(effects
				(font
					(size 1.27 1.27)
				)
			)
		)
		(property "Value" ""
			(at 0 0 270)
			(layer "F.Fab")
			(effects
				(font
					(size 1.27 1.27)
				)
			)
		)
		(duplicate_pad_numbers_are_jumpers no)
		(fp_line
			(start -0.7874 0.4064)
			(end -0.7874 -0.4064)
			(stroke
				(width 0.1524)
				(type default)
			)
			(layer "F.SilkS")
		)
		(fp_line
			(start 0.7874 0.4064)
			(end -0.7874 0.4064)
			(stroke
				(width 0.1524)
				(type default)
			)
			(layer "F.SilkS")
		)
		(fp_line
			(start -0.7874 -0.4064)
			(end 0.7874 -0.4064)
			(stroke
				(width 0.1524)
				(type default)
			)
			(layer "F.SilkS")
		)
		(fp_line
			(start 0.7874 -0.4064)
			(end 0.7874 0.4064)
			(stroke
				(width 0.1524)
				(type default)
			)
			(layer "F.SilkS")
		)
		(fp_line
			(start -0.67945 0.3048)
			(end -0.67945 -0.305054)
			(stroke
				(width 0.1)
				(type default)
			)
			(layer "F.Fab")
		)
		(fp_line
			(start -0.12065 0.3048)
			(end -0.67945 0.3048)
			(stroke
				(width 0.1)
				(type default)
			)
			(layer "F.Fab")
		)
		(fp_line
			(start 0.120396 0.3048)
			(end 0.120396 0.2794)
			(stroke
				(width 0.1)
				(type default)
			)
			(layer "F.Fab")
		)
		(fp_line
			(start 0.67945 0.3048)
			(end 0.120396 0.3048)
			(stroke
				(width 0.1)
				(type default)
			)
			(layer "F.Fab")
		)
		(fp_line
			(start -0.12065 0.2794)
			(end -0.12065 0.3048)
			(stroke
				(width 0.1)
				(type default)
			)
			(layer "F.Fab")
		)
		(fp_line
			(start 0.120396 0.2794)
			(end -0.12065 0.2794)
			(stroke
				(width 0.1)
				(type default)
			)
			(layer "F.Fab")
		)
		(fp_line
			(start -0.12065 -0.2794)
			(end 0.12065 -0.2794)
			(stroke
				(width 0.1)
				(type default)
			)
			(layer "F.Fab")
		)
		(fp_line
			(start 0.12065 -0.2794)
			(end 0.12065 -0.3048)
			(stroke
				(width 0.1)
				(type default)
			)
			(layer "F.Fab")
		)
		(fp_line
			(start 0.12065 -0.3048)
			(end 0.67945 -0.3048)
			(stroke
				(width 0.1)
				(type default)
			)
			(layer "F.Fab")
		)
		(fp_line
			(start 0.67945 -0.3048)
			(end 0.67945 0.3048)
			(stroke
				(width 0.1)
				(type default)
			)
			(layer "F.Fab")
		)
		(fp_line
			(start -0.67945 -0.305054)
			(end -0.12065 -0.305054)
			(stroke
				(width 0.1)
				(type default)
			)
			(layer "F.Fab")
		)
		(fp_line
			(start -0.12065 -0.305054)
			(end -0.12065 -0.2794)
			(stroke
				(width 0.1)
				(type default)
			)
			(layer "F.Fab")
		)
		(pad "1" smd circle
			(at -0.40005 0 270)
			(size 0 0)
			(layers "F.Cu" "F.Mask" "F.Paste")
			(net "P3V3_AUX")
		)
		(pad "2" smd circle
			(at 0.40005 0 270)
			(size 0 0)
			(layers "F.Cu" "F.Mask" "F.Paste")
			(net "GPU_FPGA_EROT_RECOV_BUF_R_N")
		)
	)
	(footprint ""
		(layer "F.Cu")
		(at 49.347882 -393.30122 180)
		(property "Reference" "R4643"
			(at 0 0 180)
			(layer "F.SilkS")
			(hide yes)
			(effects
				(font
					(size 1.27 1.27)
				)
			)
		)
		(property "Value" ""
			(at 0 0 180)
			(layer "F.Fab")
			(effects
				(font
					(size 1.27 1.27)
				)
			)
		)
		(duplicate_pad_numbers_are_jumpers no)
		(fp_line
			(start 0.7874 0.4064)
			(end -0.7874 0.4064)
			(stroke
				(width 0.1524)
				(type default)
			)
			(layer "F.SilkS")
		)
		(fp_line
			(start 0.7874 -0.4064)
			(end 0.7874 0.4064)
			(stroke
				(width 0.1524)
				(type default)
			)
			(layer "F.SilkS")
		)
		(fp_line
			(start -0.7874 0.4064)
			(end -0.7874 -0.4064)
			(stroke
				(width 0.1524)
				(type default)
			)
			(layer "F.SilkS")
		)
		(fp_line
			(start -0.7874 -0.4064)
			(end 0.7874 -0.4064)
			(stroke
				(width 0.1524)
				(type default)
			)
			(layer "F.SilkS")
		)
		(fp_line
			(start 0.67945 0.3048)
			(end 0.120396 0.3048)
			(stroke
				(width 0.1)
				(type default)
			)
			(layer "F.Fab")
		)
		(fp_line
			(start 0.67945 -0.3048)
			(end 0.67945 0.3048)
			(stroke
				(width 0.1)
				(type default)
			)
			(layer "F.Fab")
		)
		(fp_line
			(start 0.12065 -0.2794)
			(end 0.12065 -0.3048)
			(stroke
				(width 0.1)
				(type default)
			)
			(layer "F.Fab")
		)
		(fp_line
			(start 0.12065 -0.3048)
			(end 0.67945 -0.3048)
			(stroke
				(width 0.1)
				(type default)
			)
			(layer "F.Fab")
		)
		(fp_line
			(start 0.120396 0.3048)
			(end 0.120396 0.2794)
			(stroke
				(width 0.1)
				(type default)
			)
			(layer "F.Fab")
		)
		(fp_line
			(start 0.120396 0.2794)
			(end -0.12065 0.2794)
			(stroke
				(width 0.1)
				(type default)
			)
			(layer "F.Fab")
		)
		(fp_line
			(start -0.12065 0.3048)
			(end -0.67945 0.3048)
			(stroke
				(width 0.1)
				(type default)
			)
			(layer "F.Fab")
		)
		(fp_line
			(start -0.12065 0.2794)
			(end -0.12065 0.3048)
			(stroke
				(width 0.1)
				(type default)
			)
			(layer "F.Fab")
		)
		(fp_line
			(start -0.12065 -0.2794)
			(end 0.12065 -0.2794)
			(stroke
				(width 0.1)
				(type default)
			)
			(layer "F.Fab")
		)
		(fp_line
			(start -0.12065 -0.305054)
			(end -0.12065 -0.2794)
			(stroke
				(width 0.1)
				(type default)
			)
			(layer "F.Fab")
		)
		(fp_line
			(start -0.67945 0.3048)
			(end -0.67945 -0.305054)
			(stroke
				(width 0.1)
				(type default)
			)
			(layer "F.Fab")
		)
		(fp_line
			(start -0.67945 -0.305054)
			(end -0.12065 -0.305054)
			(stroke
				(width 0.1)
				(type default)
			)
			(layer "F.Fab")
		)
		(pad "1" smd circle
			(at -0.40005 0 180)
			(size 0 0)
			(layers "F.Cu" "F.Mask" "F.Paste")
			(net "P3V3_AUX")
		)
		(pad "2" smd circle
			(at 0.40005 0 180)
			(size 0 0)
			(layers "F.Cu" "F.Mask" "F.Paste")
			(net "FM_P2E_BUF2_VODA_DB")
		)
	)
	(footprint ""
		(layer "F.Cu")
		(at 176.63795 -353.62261 -90)
		(property "Reference" "PC397_P1_1"
			(at 0 0 270)
			(layer "F.SilkS")
			(hide yes)
			(effects
				(font
					(size 1.27 1.27)
				)
			)
		)
		(property "Value" ""
			(at 0 0 270)
			(layer "F.Fab")
			(effects
				(font
					(size 1.27 1.27)
				)
			)
		)
		(duplicate_pad_numbers_are_jumpers no)
		(fp_line
			(start -0.7874 0.4064)
			(end -0.7874 -0.4064)
			(stroke
				(width 0.1524)
				(type default)
			)
			(layer "F.SilkS")
		)
		(fp_line
			(start 0.7874 0.4064)
			(end -0.7874 0.4064)
			(stroke
				(width 0.1524)
				(type default)
			)
			(layer "F.SilkS")
		)
		(fp_line
			(start -0.7874 -0.4064)
			(end 0.7874 -0.4064)
			(stroke
				(width 0.1524)
				(type default)
			)
			(layer "F.SilkS")
		)
		(fp_line
			(start 0.7874 -0.4064)
			(end 0.7874 0.4064)
			(stroke
				(width 0.1524)
				(type default)
			)
			(layer "F.SilkS")
		)
		(fp_line
			(start -0.67945 0.3048)
			(end -0.67945 -0.305054)
			(stroke
				(width 0.1)
				(type default)
			)
			(layer "F.Fab")
		)
		(fp_line
			(start -0.12065 0.3048)
			(end -0.67945 0.3048)
			(stroke
				(width 0.1)
				(type default)
			)
			(layer "F.Fab")
		)
		(fp_line
			(start 0.120396 0.3048)
			(end 0.120396 0.2794)
			(stroke
				(width 0.1)
				(type default)
			)
			(layer "F.Fab")
		)
		(fp_line
			(start 0.67945 0.3048)
			(end 0.120396 0.3048)
			(stroke
				(width 0.1)
				(type default)
			)
			(layer "F.Fab")
		)
		(fp_line
			(start -0.12065 0.2794)
			(end -0.12065 0.3048)
			(stroke
				(width 0.1)
				(type default)
			)
			(layer "F.Fab")
		)
		(fp_line
			(start 0.120396 0.2794)
			(end -0.12065 0.2794)
			(stroke
				(width 0.1)
				(type default)
			)
			(layer "F.Fab")
		)
		(fp_line
			(start -0.12065 -0.2794)
			(end 0.12065 -0.2794)
			(stroke
				(width 0.1)
				(type default)
			)
			(layer "F.Fab")
		)
		(fp_line
			(start 0.12065 -0.2794)
			(end 0.12065 -0.3048)
			(stroke
				(width 0.1)
				(type default)
			)
			(layer "F.Fab")
		)
		(fp_line
			(start 0.12065 -0.3048)
			(end 0.67945 -0.3048)
			(stroke
				(width 0.1)
				(type default)
			)
			(layer "F.Fab")
		)
		(fp_line
			(start 0.67945 -0.3048)
			(end 0.67945 0.3048)
			(stroke
				(width 0.1)
				(type default)
			)
			(layer "F.Fab")
		)
		(fp_line
			(start -0.67945 -0.305054)
			(end -0.12065 -0.305054)
			(stroke
				(width 0.1)
				(type default)
			)
			(layer "F.Fab")
		)
		(fp_line
			(start -0.12065 -0.305054)
			(end -0.12065 -0.2794)
			(stroke
				(width 0.1)
				(type default)
			)
			(layer "F.Fab")
		)
		(pad "1" smd circle
			(at -0.40005 0 270)
			(size 0 0)
			(layers "F.Cu" "F.Mask" "F.Paste")
			(net "SW_P12V_PVCCFA_EHV_FIVRA_CPU1_R")
		)
		(pad "2" smd circle
			(at 0.40005 0 270)
			(size 0 0)
			(layers "F.Cu" "F.Mask" "F.Paste")
			(net "GND")
		)
	)
	(footprint ""
		(layer "F.Cu")
		(at 104.3432 -252.956568 -90)
		(property "Reference" "C261"
			(at 0 0 270)
			(layer "F.SilkS")
			(hide yes)
			(effects
				(font
					(size 1.27 1.27)
				)
			)
		)
		(property "Value" ""
			(at 0 0 270)
			(layer "F.Fab")
			(effects
				(font
					(size 1.27 1.27)
				)
			)
		)
		(duplicate_pad_numbers_are_jumpers no)
		(fp_line
			(start -0.7874 0.4064)
			(end -0.7874 -0.4064)
			(stroke
				(width 0.1524)
				(type default)
			)
			(layer "F.SilkS")
		)
		(fp_line
			(start 0.7874 0.4064)
			(end -0.7874 0.4064)
			(stroke
				(width 0.1524)
				(type default)
			)
			(layer "F.SilkS")
		)
		(fp_line
			(start -0.7874 -0.4064)
			(end 0.7874 -0.4064)
			(stroke
				(width 0.1524)
				(type default)
			)
			(layer "F.SilkS")
		)
		(fp_line
			(start 0.7874 -0.4064)
			(end 0.7874 0.4064)
			(stroke
				(width 0.1524)
				(type default)
			)
			(layer "F.SilkS")
		)
		(fp_line
			(start -0.67945 0.3048)
			(end -0.67945 -0.305054)
			(stroke
				(width 0.1)
				(type default)
			)
			(layer "F.Fab")
		)
		(fp_line
			(start -0.12065 0.3048)
			(end -0.67945 0.3048)
			(stroke
				(width 0.1)
				(type default)
			)
			(layer "F.Fab")
		)
		(fp_line
			(start 0.120396 0.3048)
			(end 0.120396 0.2794)
			(stroke
				(width 0.1)
				(type default)
			)
			(layer "F.Fab")
		)
		(fp_line
			(start 0.67945 0.3048)
			(end 0.120396 0.3048)
			(stroke
				(width 0.1)
				(type default)
			)
			(layer "F.Fab")
		)
		(fp_line
			(start -0.12065 0.2794)
			(end -0.12065 0.3048)
			(stroke
				(width 0.1)
				(type default)
			)
			(layer "F.Fab")
		)
		(fp_line
			(start 0.120396 0.2794)
			(end -0.12065 0.2794)
			(stroke
				(width 0.1)
				(type default)
			)
			(layer "F.Fab")
		)
		(fp_line
			(start -0.12065 -0.2794)
			(end 0.12065 -0.2794)
			(stroke
				(width 0.1)
				(type default)
			)
			(layer "F.Fab")
		)
		(fp_line
			(start 0.12065 -0.2794)
			(end 0.12065 -0.3048)
			(stroke
				(width 0.1)
				(type default)
			)
			(layer "F.Fab")
		)
		(fp_line
			(start 0.12065 -0.3048)
			(end 0.67945 -0.3048)
			(stroke
				(width 0.1)
				(type default)
			)
			(layer "F.Fab")
		)
		(fp_line
			(start 0.67945 -0.3048)
			(end 0.67945 0.3048)
			(stroke
				(width 0.1)
				(type default)
			)
			(layer "F.Fab")
		)
		(fp_line
			(start -0.67945 -0.305054)
			(end -0.12065 -0.305054)
			(stroke
				(width 0.1)
				(type default)
			)
			(layer "F.Fab")
		)
		(fp_line
			(start -0.12065 -0.305054)
			(end -0.12065 -0.2794)
			(stroke
				(width 0.1)
				(type default)
			)
			(layer "F.Fab")
		)
		(pad "1" smd circle
			(at -0.40005 0 270)
			(size 0 0)
			(layers "F.Cu" "F.Mask" "F.Paste")
			(net "PVCCIN_CPU1")
		)
		(pad "2" smd circle
			(at 0.40005 0 270)
			(size 0 0)
			(layers "F.Cu" "F.Mask" "F.Paste")
			(net "GND")
		)
	)
	(footprint ""
		(layer "F.Cu")
		(at 421.801544 -46.5455 -90)
		(property "Reference" "D7"
			(at 2.457958 1.281684 0)
			(unlocked yes)
			(layer "F.SilkS")
			(effects
				(font
					(size 0.7874 0.5842)
					(thickness 0.1524)
				)
				(justify left)
			)
		)
		(property "Value" ""
			(at 0 0 270)
			(layer "F.Fab")
			(effects
				(font
					(size 1.27 1.27)
				)
			)
		)
		(duplicate_pad_numbers_are_jumpers no)
		(fp_line
			(start -1.584198 1.500124)
			(end 1.584198 1.500124)
			(stroke
				(width 0.1524)
				(type default)
			)
			(layer "F.SilkS")
		)
		(fp_line
			(start 1.584198 1.500124)
			(end 1.584198 -1.500124)
			(stroke
				(width 0.1524)
				(type default)
			)
			(layer "F.SilkS")
		)
		(fp_line
			(start -1.584198 -1.500124)
			(end -1.584198 1.500124)
			(stroke
				(width 0.1524)
				(type default)
			)
			(layer "F.SilkS")
		)
		(fp_line
			(start 1.584198 -1.500124)
			(end -1.584198 -1.500124)
			(stroke
				(width 0.1524)
				(type default)
			)
			(layer "F.SilkS")
		)
		(fp_line
			(start -0.700024 1.500124)
			(end 0.700024 1.500124)
			(stroke
				(width 0.1)
				(type default)
			)
			(layer "F.Fab")
		)
		(fp_line
			(start 0.700024 1.500124)
			(end 0.700024 -1.500124)
			(stroke
				(width 0.1)
				(type default)
			)
			(layer "F.Fab")
		)
		(fp_line
			(start -0.700024 -1.500124)
			(end -0.700024 1.500124)
			(stroke
				(width 0.1)
				(type default)
			)
			(layer "F.Fab")
		)
		(fp_line
			(start 0.700024 -1.500124)
			(end -0.700024 -1.500124)
			(stroke
				(width 0.1)
				(type default)
			)
			(layer "F.Fab")
		)
		(pad "1" smd rect
			(at -0.999998 -0.94996 180)
			(size 0.8128 0.9144)
			(layers "F.Cu" "F.Mask" "F.Paste")
			(net "P3V3")
		)
		(pad "2" smd rect
			(at -0.999998 0.94996 180)
			(size 0.8128 0.9144)
			(layers "F.Cu" "F.Mask" "F.Paste")
			(net "Net_8589")
		)
		(pad "3" smd rect
			(at 0.999998 0 180)
			(size 0.8128 0.9144)
			(layers "F.Cu" "F.Mask" "F.Paste")
			(net "P5V")
		)
	)
	(footprint ""
		(layer "F.Cu")
		(at 381.93345 -408.517344 -90)
		(property "Reference" "C876"
			(at 0 0 270)
			(layer "F.SilkS")
			(hide yes)
			(effects
				(font
					(size 1.27 1.27)
				)
			)
		)
		(property "Value" ""
			(at 0 0 270)
			(layer "F.Fab")
			(effects
				(font
					(size 1.27 1.27)
				)
			)
		)
		(duplicate_pad_numbers_are_jumpers no)
		(fp_line
			(start -0.299974 0.150114)
			(end -0.299974 -0.150114)
			(stroke
				(width 0.1)
				(type default)
			)
			(layer "F.Fab")
		)
		(fp_line
			(start 0.299974 0.150114)
			(end -0.299974 0.150114)
			(stroke
				(width 0.1)
				(type default)
			)
			(layer "F.Fab")
		)
		(fp_line
			(start -0.299974 -0.150114)
			(end 0.299974 -0.150114)
			(stroke
				(width 0.1)
				(type default)
			)
			(layer "F.Fab")
		)
		(fp_line
			(start 0.299974 -0.150114)
			(end 0.299974 0.150114)
			(stroke
				(width 0.1)
				(type default)
			)
			(layer "F.Fab")
		)
		(pad "1" smd rect
			(at -0.2667 0 270)
			(size 0.3048 0.381)
			(layers "F.Cu" "F.Mask" "F.Paste")
			(net "P5E_CPU0_PE3_TX_C_DN<12>")
		)
		(pad "2" smd rect
			(at 0.2667 0 270)
			(size 0.3048 0.381)
			(layers "F.Cu" "F.Mask" "F.Paste")
			(net "P5E_CPU0_PE3_TX_DN<12>")
		)
	)
)
